(kicad_pcb
	(version 20260206)
	(generator "pcbnew")
	(generator_version "10.0")
	(general
		(thickness 1.6)
		(legacy_teardrops no)
	)
	(paper "A4")
	(title_block
		(title "v2-tray-backplane — ms_tbp_v2.brd")
		(comment 1 "Open CloudServer (Microsoft) / footprints 15-16 of 164")
	)
	(layers
		(0 "F.Cu" signal "TOP")
		(4 "In1.Cu" signal "LYR2")
		(6 "In2.Cu" signal "LYR3")
		(8 "In3.Cu" signal "LYR4")
		(10 "In4.Cu" signal "LYR5")
		(12 "In5.Cu" signal "LYR6")
		(14 "In6.Cu" signal "LYR7")
		(2 "B.Cu" signal "BOTTOM")
		(9 "F.Adhes" user "F.Adhesive")
		(11 "B.Adhes" user "B.Adhesive")
		(13 "F.Paste" user "Package Geometry/Pastemask Top")
		(15 "B.Paste" user "Package Geometry/Pastemask Bottom")
		(5 "F.SilkS" user "Ref Des/Silkscreen Top")
		(7 "B.SilkS" user "Ref Des/Silkscreen Bottom")
		(1 "F.Mask" user "Board Geometry/Soldermask Top")
		(3 "B.Mask" user "Board Geometry/Soldermask Bottom")
		(17 "Dwgs.User" user "User.Drawings")
		(19 "Cmts.User" user "User.Comments")
		(21 "Eco1.User" user "User.Eco1")
		(23 "Eco2.User" user "User.Eco2")
		(25 "Edge.Cuts" user "Board Geometry/Outline")
		(27 "Margin" user)
		(31 "F.CrtYd" user "Package Geometry/Place Bound Top")
		(29 "B.CrtYd" user "Package Geometry/Place Bound Bottom")
		(35 "F.Fab" user "Ref Des/Assembly Top")
		(33 "B.Fab" user "Ref Des/Assembly Bottom")
	)
	(footprint ""
		(layer "F.Cu")
		(at -316.25 39.010001 180)
		(property "Reference" "J8"
			(at 8.91572 -8.726759 0)
			(unlocked yes)
			(layer "F.SilkS")
			(effects
				(font
					(size 0.762 0.5334)
					(thickness 0.1016)
				)
			)
		)
		(property "Value" ""
			(at 0 0 180)
			(layer "F.Fab")
			(effects
				(font
					(size 1.27 1.27)
				)
			)
		)
		(duplicate_pad_numbers_are_jumpers no)
		(fp_line
			(start 9.1 5.750001)
			(end 9.1 4.093401)
			(stroke
				(width 0.127)
				(type default)
			)
			(layer "F.SilkS")
		)
		(fp_line
			(start 9.1 -5.750001)
			(end 9.1 1.507599)
			(stroke
				(width 0.127)
				(type default)
			)
			(layer "F.SilkS")
		)
		(fp_line
			(start 7.5211 -5.750001)
			(end 9.1 -5.750001)
			(stroke
				(width 0.127)
				(type default)
			)
			(layer "F.SilkS")
		)
		(fp_line
			(start -8.029301 -5.750001)
			(end -9.1 -5.750001)
			(stroke
				(width 0.127)
				(type default)
			)
			(layer "F.SilkS")
		)
		(fp_line
			(start -9.1 5.750001)
			(end 9.1 5.750001)
			(stroke
				(width 0.127)
				(type default)
			)
			(layer "F.SilkS")
		)
		(fp_line
			(start -9.1 4.0408)
			(end -9.1 5.750001)
			(stroke
				(width 0.127)
				(type default)
			)
			(layer "F.SilkS")
		)
		(fp_line
			(start -9.1 -5.750001)
			(end -9.1 1.446101)
			(stroke
				(width 0.127)
				(type default)
			)
			(layer "F.SilkS")
		)
		(fp_rect
			(start -9.608 6.258001)
			(end 9.607999 -6.258002)
			(stroke
				(width 0)
				(type default)
			)
			(fill no)
			(layer "F.CrtYd")
		)
		(fp_line
			(start 9.1 5.750001)
			(end 9.1 -5.750001)
			(stroke
				(width 0.1)
				(type default)
			)
			(layer "F.Fab")
		)
		(fp_line
			(start 9.1 -5.750001)
			(end -9.1 -5.750001)
			(stroke
				(width 0.1)
				(type default)
			)
			(layer "F.Fab")
		)
		(fp_line
			(start -9.1 5.750001)
			(end 9.1 5.750001)
			(stroke
				(width 0.1)
				(type default)
			)
			(layer "F.Fab")
		)
		(fp_line
			(start -9.1 -5.750001)
			(end -9.1 5.750001)
			(stroke
				(width 0.1)
				(type default)
			)
			(layer "F.Fab")
		)
		(fp_text user "19"
			(at 8.41026 -0.309199 0)
			(unlocked yes)
			(layer "F.SilkS")
			(effects
				(font
					(size 0.762 0.5334)
					(thickness 0.1016)
				)
			)
		)
		(fp_text user "20"
			(at 8.0445 -3.941399 0)
			(unlocked yes)
			(layer "F.SilkS")
			(effects
				(font
					(size 0.762 0.5334)
					(thickness 0.1016)
				)
			)
		)
		(fp_text user "*"
			(at -8.06926 -0.909909 0)
			(unlocked yes)
			(layer "F.SilkS")
			(effects
				(font
					(size 0.381 0.381)
					(thickness 0.381)
				)
			)
		)
		(pad "" np_thru_hole circle
			(at -8.400001 2.849999 270)
			(size 1.27 1.27)
			(drill 1.5494)
			(layers "*.Cu" "*.Mask")
		)
		(pad "" np_thru_hole circle
			(at 8.400001 2.849999 270)
			(size 1.27 1.27)
			(drill 1.5494)
			(layers "*.Cu" "*.Mask")
		)
		(pad "1" smd oval
			(at -7.000001 -2.33 180)
			(size 0.3556 1.8034)
			(layers "F.Cu" "F.Mask" "F.Paste")
			(net "GND")
		)
		(pad "2" smd oval
			(at -6.2 -2.33 180)
			(size 0.3556 1.8034)
			(layers "F.Cu" "F.Mask" "F.Paste")
			(net "ETH40G_B1_TX1N")
		)
		(pad "3" smd oval
			(at -5.399999 -2.33 180)
			(size 0.3556 1.8034)
			(layers "F.Cu" "F.Mask" "F.Paste")
			(net "ETH40G_B1_TX1P")
		)
		(pad "4" smd oval
			(at -4.600001 -2.33 180)
			(size 0.3556 1.8034)
			(layers "F.Cu" "F.Mask" "F.Paste")
			(net "GND")
		)
		(pad "5" smd oval
			(at -3.8 -2.33 180)
			(size 0.3556 1.8034)
			(layers "F.Cu" "F.Mask" "F.Paste")
			(net "ETH40G_B1_TX3N")
		)
		(pad "6" smd oval
			(at -2.999999 -2.33 180)
			(size 0.3556 1.8034)
			(layers "F.Cu" "F.Mask" "F.Paste")
			(net "ETH40G_B1_TX3P")
		)
		(pad "7" smd oval
			(at -2.200001 -2.33 180)
			(size 0.3556 1.8034)
			(layers "F.Cu" "F.Mask" "F.Paste")
			(net "GND")
		)
		(pad "8" smd oval
			(at -1.4 -2.33 180)
			(size 0.3556 1.8034)
			(layers "F.Cu" "F.Mask" "F.Paste")
			(net "ETH40G_B1_MODSEL_N")
		)
		(pad "9" smd oval
			(at -0.599999 -2.33 180)
			(size 0.3556 1.8034)
			(layers "F.Cu" "F.Mask" "F.Paste")
			(net "ETH40G_B1_RESET_N")
		)
		(pad "10" smd oval
			(at 0.2 -2.33 180)
			(size 0.3556 1.8034)
			(layers "F.Cu" "F.Mask" "F.Paste")
			(net "P3V3_40G_B1_VCC_RX")
		)
		(pad "11" smd oval
			(at 1.000001 -2.33 180)
			(size 0.3556 1.8034)
			(layers "F.Cu" "F.Mask" "F.Paste")
			(net "ETH40G_B1_SCL")
		)
		(pad "12" smd oval
			(at 1.799999 -2.33 180)
			(size 0.3556 1.8034)
			(layers "F.Cu" "F.Mask" "F.Paste")
			(net "ETH40G_B1_SDA")
		)
		(pad "13" smd oval
			(at 2.6 -2.33 180)
			(size 0.3556 1.8034)
			(layers "F.Cu" "F.Mask" "F.Paste")
			(net "GND")
		)
		(pad "14" smd oval
			(at 3.400001 -2.33 180)
			(size 0.3556 1.8034)
			(layers "F.Cu" "F.Mask" "F.Paste")
			(net "ETH40G_B1_RX2P")
		)
		(pad "15" smd oval
			(at 4.199999 -2.33 180)
			(size 0.3556 1.8034)
			(layers "F.Cu" "F.Mask" "F.Paste")
			(net "ETH40G_B1_RX2N")
		)
		(pad "16" smd oval
			(at 5 -2.33 180)
			(size 0.3556 1.8034)
			(layers "F.Cu" "F.Mask" "F.Paste")
			(net "GND")
		)
		(pad "17" smd oval
			(at 5.800001 -2.33 180)
			(size 0.3556 1.8034)
			(layers "F.Cu" "F.Mask" "F.Paste")
			(net "ETH40G_B1_RX0P")
		)
		(pad "18" smd oval
			(at 6.6 -2.33 180)
			(size 0.3556 1.8034)
			(layers "F.Cu" "F.Mask" "F.Paste")
			(net "ETH40G_B1_RX0N")
		)
		(pad "19" smd oval
			(at 7.4 -2.33 180)
			(size 0.3556 1.8034)
			(layers "F.Cu" "F.Mask" "F.Paste")
			(net "GND")
		)
		(pad "20" smd oval
			(at 7.000001 -4.830001 180)
			(size 0.3556 1.8034)
			(layers "F.Cu" "F.Mask" "F.Paste")
			(net "GND")
		)
		(pad "21" smd oval
			(at 6.2 -4.830001 180)
			(size 0.3556 1.8034)
			(layers "F.Cu" "F.Mask" "F.Paste")
			(net "ETH40G_B1_RX1N")
		)
		(pad "22" smd oval
			(at 5.399999 -4.830001 180)
			(size 0.3556 1.8034)
			(layers "F.Cu" "F.Mask" "F.Paste")
			(net "ETH40G_B1_RX1P")
		)
		(pad "23" smd oval
			(at 4.600001 -4.830001 180)
			(size 0.3556 1.8034)
			(layers "F.Cu" "F.Mask" "F.Paste")
			(net "GND")
		)
		(pad "24" smd oval
			(at 3.8 -4.830001 180)
			(size 0.3556 1.8034)
			(layers "F.Cu" "F.Mask" "F.Paste")
			(net "ETH40G_B1_RX3N")
		)
		(pad "25" smd oval
			(at 2.999999 -4.830001 180)
			(size 0.3556 1.8034)
			(layers "F.Cu" "F.Mask" "F.Paste")
			(net "ETH40G_B1_RX3P")
		)
		(pad "26" smd oval
			(at 2.200001 -4.830001 180)
			(size 0.3556 1.8034)
			(layers "F.Cu" "F.Mask" "F.Paste")
			(net "GND")
		)
		(pad "27" smd oval
			(at 1.4 -4.830001 180)
			(size 0.3556 1.8034)
			(layers "F.Cu" "F.Mask" "F.Paste")
			(net "ETH40G_B1_MODPRS_N")
		)
		(pad "28" smd oval
			(at 0.599999 -4.830001 180)
			(size 0.3556 1.8034)
			(layers "F.Cu" "F.Mask" "F.Paste")
			(net "ETH40G_B1_INT_N")
		)
		(pad "29" smd oval
			(at -0.2 -4.830001 180)
			(size 0.3556 1.8034)
			(layers "F.Cu" "F.Mask" "F.Paste")
			(net "P3V3_40G_B1_VCC_TX")
		)
		(pad "30" smd oval
			(at -1.000001 -4.830001 180)
			(size 0.3556 1.8034)
			(layers "F.Cu" "F.Mask" "F.Paste")
			(net "P3V3_40G_B1_VCC1")
		)
		(pad "31" smd oval
			(at -1.799999 -4.830001 180)
			(size 0.3556 1.8034)
			(layers "F.Cu" "F.Mask" "F.Paste")
			(net "ETH40G_B1_LPMODE")
		)
		(pad "32" smd oval
			(at -2.6 -4.830001 180)
			(size 0.3556 1.8034)
			(layers "F.Cu" "F.Mask" "F.Paste")
			(net "GND")
		)
		(pad "33" smd oval
			(at -3.400001 -4.830001 180)
			(size 0.3556 1.8034)
			(layers "F.Cu" "F.Mask" "F.Paste")
			(net "ETH40G_B1_TX2P")
		)
		(pad "34" smd oval
			(at -4.199999 -4.830001 180)
			(size 0.3556 1.8034)
			(layers "F.Cu" "F.Mask" "F.Paste")
			(net "ETH40G_B1_TX2N")
		)
		(pad "35" smd oval
			(at -5 -4.830001 180)
			(size 0.3556 1.8034)
			(layers "F.Cu" "F.Mask" "F.Paste")
			(net "GND")
		)
		(pad "36" smd oval
			(at -5.800001 -4.830001 180)
			(size 0.3556 1.8034)
			(layers "F.Cu" "F.Mask" "F.Paste")
			(net "ETH40G_B1_TX0P")
		)
		(pad "37" smd oval
			(at -6.6 -4.830001 180)
			(size 0.3556 1.8034)
			(layers "F.Cu" "F.Mask" "F.Paste")
			(net "ETH40G_B1_TX0N")
		)
		(pad "38" smd oval
			(at -7.4 -4.830001 180)
			(size 0.3556 1.8034)
			(layers "F.Cu" "F.Mask" "F.Paste")
			(net "GND")
		)
		(zone
			(layers "F.Cu" "B.Cu" "In1.Cu" "In2.Cu" "In3.Cu" "In4.Cu" "In5.Cu" "In6.Cu")
			(hatch none 0.5)
			(connect_pads
				(clearance 0)
			)
			(min_thickness 0.25)
			(keepout
				(tracks not_allowed)
				(vias allowed)
				(pads allowed)
				(copperpour not_allowed)
				(footprints allowed)
			)
			(placement
				(enabled no)
				(sheetname "")
			)
			(fill
				(thermal_gap 0.5)
				(thermal_bridge_width 0.5)
				(island_removal_mode 0)
			)
			(polygon
				(pts
					(arc
						(start -325.805701 36.160001)
						(mid -323.494301 36.160001)
						(end -325.805701 36.160001)
					)
				)
			)
		)
		(zone
			(layers "F.Cu" "B.Cu" "In1.Cu" "In2.Cu" "In3.Cu" "In4.Cu" "In5.Cu" "In6.Cu")
			(hatch none 0.5)
			(connect_pads
				(clearance 0)
			)
			(min_thickness 0.25)
			(keepout
				(tracks not_allowed)
				(vias allowed)
				(pads allowed)
				(copperpour not_allowed)
				(footprints allowed)
			)
			(placement
				(enabled no)
				(sheetname "")
			)
			(fill
				(thermal_gap 0.5)
				(thermal_bridge_width 0.5)
				(island_removal_mode 0)
			)
			(polygon
				(pts
					(arc
						(start -309.005699 36.160001)
						(mid -306.694299 36.160001)
						(end -309.005699 36.160001)
					)
				)
			)
		)
	)
	(footprint ""
		(layer "F.Cu")
		(at -300.99 11.811)
		(property "Reference" "R80"
			(at -3.175 0.0381 0)
			(unlocked yes)
			(layer "F.SilkS")
			(effects
				(font
					(size 0.762 0.5334)
					(thickness 0.1016)
				)
			)
		)
		(property "Value" ""
			(at 0 0 0)
			(layer "F.Fab")
			(effects
				(font
					(size 1.27 1.27)
				)
			)
		)
		(duplicate_pad_numbers_are_jumpers no)
		(fp_line
			(start 0 -0.381)
			(end 0 0.381)
			(stroke
				(width 0.127)
				(type default)
			)
			(layer "F.SilkS")
		)
		(fp_poly
			(pts
				(xy 1.255601 0.6564) (xy -1.255601 0.6564) (xy -1.255601 -0.656399) (xy 1.255601 -0.656399)
			)
			(stroke
				(width 0)
				(type default)
			)
			(fill no)
			(layer "F.CrtYd")
		)
		(fp_line
			(start -0.800001 -0.399999)
			(end -0.800001 0.399999)
			(stroke
				(width 0.1)
				(type default)
			)
			(layer "F.Fab")
		)
		(fp_line
			(start -0.800001 0.399999)
			(end 0.800001 0.399999)
			(stroke
				(width 0.1)
				(type default)
			)
			(layer "F.Fab")
		)
		(fp_line
			(start 0.800001 -0.399999)
			(end -0.800001 -0.399999)
			(stroke
				(width 0.1)
				(type default)
			)
			(layer "F.Fab")
		)
		(fp_line
			(start 0.800001 0.399999)
			(end 0.800001 -0.399999)
			(stroke
				(width 0.1)
				(type default)
			)
			(layer "F.Fab")
		)
		(pad "1" smd rect
			(at -0.650001 0)
			(size 0.7112 0.8128)
			(layers "F.Cu" "F.Mask" "F.Paste")
			(net "ETH40G_B1_MODPRS_N")
		)
		(pad "2" smd rect
			(at 0.650001 0 180)
			(size 0.7112 0.8128)
			(layers "F.Cu" "F.Mask" "F.Paste")
			(net "ETH40G_B1_PRES_N")
		)
	)
)
